(kicad_pcb
	(version 20260206)
	(generator "pcbnew")
	(generator_version "10.0")
	(general
		(thickness 1.6)
		(legacy_teardrops no)
	)
	(paper "A4")
	(title_block
		(title "fcb — Lightning_FCB_BRD.brd")
		(comment 1 "Lightning (Wiwynn / Facebook NVMe JBOF) / footprints 357-363 of 495")
	)
	(layers
		(0 "F.Cu" signal "TOP")
		(4 "In1.Cu" signal "L2GND")
		(6 "In2.Cu" signal "L3VCC")
		(2 "B.Cu" signal "BOTTOM")
		(9 "F.Adhes" user "F.Adhesive")
		(11 "B.Adhes" user "B.Adhesive")
		(13 "F.Paste" user "Package Geometry/Pastemask Top")
		(15 "B.Paste" user "Package Geometry/Pastemask Bottom")
		(5 "F.SilkS" user "Ref Des/Silkscreen Top")
		(7 "B.SilkS" user "Ref Des/Silkscreen Bottom")
		(1 "F.Mask" user "Board Geometry/Soldermask Top")
		(3 "B.Mask" user "Board Geometry/Soldermask Bottom")
		(17 "Dwgs.User" user "User.Drawings")
		(19 "Cmts.User" user "User.Comments")
		(21 "Eco1.User" user "User.Eco1")
		(23 "Eco2.User" user "User.Eco2")
		(25 "Edge.Cuts" user "Board Geometry/Outline")
		(27 "Margin" user)
		(31 "F.CrtYd" user "Package Geometry/Place Bound Top")
		(29 "B.CrtYd" user "Package Geometry/Place Bound Bottom")
		(35 "F.Fab" user "Ref Des/Assembly Top")
		(33 "B.Fab" user "Ref Des/Assembly Bottom")
	)
	(footprint ""
		(layer "F.Cu")
		(at 38.024816 -354.076 -90)
		(property "Reference" "R363"
			(at 0 0 270)
			(layer "F.SilkS")
			(hide yes)
			(effects
				(font
					(size 1.27 1.27)
				)
			)
		)
		(property "Value" "5K1R2F-2-GP"
			(at 0.064008 -3.993896 270)
			(unlocked yes)
			(layer "F.Fab")
			(hide yes)
			(effects
				(font
					(size 1.016 1.016)
					(thickness 0.1524)
				)
			)
		)
		(property "Device Type" "R402H16"
			(at 0.064008 -5.517896 270)
			(unlocked yes)
			(layer "F.Fab")
			(hide yes)
			(effects
				(font
					(size 1.016 1.016)
					(thickness 0.1524)
				)
			)
		)
		(duplicate_pad_numbers_are_jumpers no)
		(fp_line
			(start -0.508 -0.9398)
			(end -0.508 0.9398)
			(stroke
				(width 0.1524)
				(type default)
			)
			(layer "F.SilkS")
		)
		(fp_line
			(start 0.508 -0.9398)
			(end -0.508 -0.9398)
			(stroke
				(width 0.1524)
				(type default)
			)
			(layer "F.SilkS")
		)
		(fp_rect
			(start -0.508 0.9398)
			(end 0.508 -0.9398)
			(stroke
				(width 0)
				(type default)
			)
			(fill no)
			(layer "F.CrtYd")
		)
		(fp_rect
			(start -0.508 0.9398)
			(end 0.508 -0.9398)
			(stroke
				(width 0)
				(type default)
			)
			(fill no)
			(layer "F.Fab")
		)
		(pad "1" smd custom
			(at 0 -0.4445 270)
			(size 0.1397 0.1397)
			(layers "F.Cu" "F.Mask" "F.Paste")
			(net "OTP_RETRY_B")
			(options
				(clearance outline)
				(anchor circle)
			)
			(primitives
				(gr_poly
					(pts
						(arc
							(start -0.1778 -0.2794)
							(mid -0.249642 -0.249642)
							(end -0.2794 -0.1778)
						)
						(arc
							(start -0.2794 0.1778)
							(mid -0.249642 0.249642)
							(end -0.1778 0.2794)
						)
						(arc
							(start 0.1778 0.2794)
							(mid 0.249642 0.249642)
							(end 0.2794 0.1778)
						)
						(arc
							(start 0.2794 -0.1778)
							(mid 0.249642 -0.249642)
							(end 0.1778 -0.2794)
						)
					)
					(width 0)
					(fill yes)
				)
			)
		)
		(pad "2" smd custom
			(at 0 0.4445 270)
			(size 0.1397 0.1397)
			(layers "F.Cu" "F.Mask" "F.Paste")
			(net "GND")
			(options
				(clearance outline)
				(anchor circle)
			)
			(primitives
				(gr_poly
					(pts
						(arc
							(start -0.1778 -0.2794)
							(mid -0.249642 -0.249642)
							(end -0.2794 -0.1778)
						)
						(arc
							(start -0.2794 0.1778)
							(mid -0.249642 0.249642)
							(end -0.1778 0.2794)
						)
						(arc
							(start 0.1778 0.2794)
							(mid 0.249642 0.249642)
							(end 0.2794 0.1778)
						)
						(arc
							(start 0.2794 -0.1778)
							(mid 0.249642 -0.249642)
							(end 0.1778 -0.2794)
						)
					)
					(width 0)
					(fill yes)
				)
			)
		)
	)
	(footprint ""
		(layer "F.Cu")
		(at 40.132 -122.428)
		(property "Reference" "PR63"
			(at 0 0 0)
			(layer "F.SilkS")
			(hide yes)
			(effects
				(font
					(size 1.27 1.27)
				)
			)
		)
		(property "Value" "D002R2512F-GP"
			(at -3.228594 -1.194054 0)
			(unlocked yes)
			(layer "F.Fab")
			(hide yes)
			(effects
				(font
					(size 1.016 1.016)
					(thickness 0.1524)
				)
			)
		)
		(property "Device Type" "R2512-2H32"
			(at -3.228594 -2.718054 0)
			(unlocked yes)
			(layer "F.Fab")
			(hide yes)
			(effects
				(font
					(size 1.016 1.016)
					(thickness 0.1524)
				)
			)
		)
		(duplicate_pad_numbers_are_jumpers no)
		(fp_line
			(start -1.9685 -3.81)
			(end 1.9685 -3.81)
			(stroke
				(width 0.1524)
				(type default)
			)
			(layer "F.SilkS")
		)
		(fp_line
			(start -1.9685 3.81)
			(end -1.9685 -3.81)
			(stroke
				(width 0.1524)
				(type default)
			)
			(layer "F.SilkS")
		)
		(fp_line
			(start 1.9685 -3.81)
			(end 1.9685 3.81)
			(stroke
				(width 0.1524)
				(type default)
			)
			(layer "F.SilkS")
		)
		(fp_line
			(start 1.9685 3.81)
			(end -1.9685 3.81)
			(stroke
				(width 0.1524)
				(type default)
			)
			(layer "F.SilkS")
		)
		(fp_rect
			(start -1.5875 3.175)
			(end 1.5875 -3.175)
			(stroke
				(width 0)
				(type default)
			)
			(fill no)
			(layer "F.CrtYd")
		)
		(fp_poly
			(pts
				(xy -2.2225 3.8862) (xy -2.2225 0.00254) (xy -1.5875 0.00254) (xy -1.5875 3.175) (xy 1.5875 3.175)
				(xy 1.5875 -3.175) (xy -1.5875 -3.175) (xy -1.5875 -0.00254) (xy -2.2225 -0.00254) (xy -2.2225 -3.8862)
				(xy 2.2225 -3.8862) (xy 2.2225 3.8862)
			)
			(stroke
				(width 0)
				(type default)
			)
			(fill no)
			(layer "F.CrtYd")
		)
		(fp_rect
			(start -2.2225 3.8862)
			(end 2.2225 -3.8862)
			(stroke
				(width 0)
				(type default)
			)
			(fill no)
			(layer "F.Fab")
		)
		(pad "1" smd rect
			(at 0 -2.273808)
			(size 3.429 2.5654)
			(layers "F.Cu" "F.Mask" "F.Paste")
			(net "P12V")
		)
		(pad "2" smd rect
			(at 0 2.273808)
			(size 3.429 2.5654)
			(layers "F.Cu" "F.Mask" "F.Paste")
			(net "P12VL_NET")
		)
	)
	(footprint ""
		(layer "F.Cu")
		(at 7.112 -452.374 90)
		(property "Reference" "D11"
			(at 0 0 90)
			(layer "F.SilkS")
			(hide yes)
			(effects
				(font
					(size 1.27 1.27)
				)
			)
		)
		(property "Value" "BAS16H-GP"
			(at 0 -5.5372 90)
			(unlocked yes)
			(layer "F.Fab")
			(hide yes)
			(effects
				(font
					(size 1.016 1.016)
					(thickness 0.1524)
				)
			)
		)
		(property "Device Type" "SOD123AKH48"
			(at 0 -7.0612 90)
			(unlocked yes)
			(layer "F.Fab")
			(hide yes)
			(effects
				(font
					(size 1.016 1.016)
					(thickness 0.1524)
				)
			)
		)
		(duplicate_pad_numbers_are_jumpers no)
		(fp_line
			(start 1.016 -2.667)
			(end -1.016 -2.667)
			(stroke
				(width 0.1524)
				(type default)
			)
			(layer "F.SilkS")
		)
		(fp_line
			(start -1.016 -2.667)
			(end -1.016 2.667)
			(stroke
				(width 0.1524)
				(type default)
			)
			(layer "F.SilkS")
		)
		(fp_line
			(start 1.016 2.667)
			(end 1.016 -2.667)
			(stroke
				(width 0.1524)
				(type default)
			)
			(layer "F.SilkS")
		)
		(fp_line
			(start -1.016 2.667)
			(end 1.016 2.667)
			(stroke
				(width 0.1524)
				(type default)
			)
			(layer "F.SilkS")
		)
		(fp_line
			(start 0.889 2.921)
			(end -0.889 2.921)
			(stroke
				(width 0.508)
				(type default)
			)
			(layer "F.SilkS")
		)
		(fp_rect
			(start -1.143 3.175)
			(end 1.143 -2.794)
			(stroke
				(width 0)
				(type default)
			)
			(fill no)
			(layer "F.CrtYd")
		)
		(fp_poly
			(pts
				(xy -1.143 -2.794) (xy 1.143 -2.794) (xy 1.143 3.175) (xy -1.143 3.175)
			)
			(stroke
				(width 0)
				(type default)
			)
			(fill no)
			(layer "F.Fab")
		)
		(pad "A" smd rect
			(at 0 -1.6891 90)
			(size 0.889 1.397)
			(layers "F.Cu" "F.Mask" "F.Paste")
			(net "FAN_TACH1")
		)
		(pad "K" smd rect
			(at 0 1.6891 90)
			(size 0.889 1.397)
			(layers "F.Cu" "F.Mask" "F.Paste")
			(net "P12V")
		)
	)
	(footprint ""
		(layer "F.Cu")
		(at 8.4836 -62.7126 -90)
		(property "Reference" "R122"
			(at 0 0 270)
			(layer "F.SilkS")
			(hide yes)
			(effects
				(font
					(size 1.27 1.27)
				)
			)
		)
		(property "Value" "1K8R6J-GP"
			(at -0.0508 -4.8514 270)
			(unlocked yes)
			(layer "F.Fab")
			(hide yes)
			(effects
				(font
					(size 1.016 1.016)
					(thickness 0.1524)
				)
			)
		)
		(property "Device Type" "R1206H28"
			(at 0 -6.3754 270)
			(unlocked yes)
			(layer "F.Fab")
			(hide yes)
			(effects
				(font
					(size 1.016 1.016)
					(thickness 0.1524)
				)
			)
		)
		(duplicate_pad_numbers_are_jumpers no)
		(fp_line
			(start -1.016 2.2352)
			(end -1.016 -2.2352)
			(stroke
				(width 0.1524)
				(type default)
			)
			(layer "F.SilkS")
		)
		(fp_line
			(start 1.016 2.2352)
			(end -1.016 2.2352)
			(stroke
				(width 0.1524)
				(type default)
			)
			(layer "F.SilkS")
		)
		(fp_line
			(start -1.016 -2.2352)
			(end 1.016 -2.2352)
			(stroke
				(width 0.1524)
				(type default)
			)
			(layer "F.SilkS")
		)
		(fp_line
			(start 1.016 -2.2352)
			(end 1.016 2.2352)
			(stroke
				(width 0.1524)
				(type default)
			)
			(layer "F.SilkS")
		)
		(fp_rect
			(start -1.0922 2.3114)
			(end 1.0922 -2.3114)
			(stroke
				(width 0)
				(type default)
			)
			(fill no)
			(layer "F.CrtYd")
		)
		(fp_poly
			(pts
				(xy -1.0922 -2.3114) (xy 1.0922 -2.3114) (xy 1.0922 2.3114) (xy -1.0922 2.3114)
			)
			(stroke
				(width 0)
				(type default)
			)
			(fill no)
			(layer "F.Fab")
		)
		(pad "1" smd rect
			(at 0 -1.397 270)
			(size 1.651 1.27)
			(layers "F.Cu" "F.Mask" "F.Paste")
			(net "P12V")
		)
		(pad "2" smd rect
			(at 0 1.397 270)
			(size 1.651 1.27)
			(layers "F.Cu" "F.Mask" "F.Paste")
			(net "LED_DR_LED5_BLUE")
		)
	)
	(footprint ""
		(layer "F.Cu")
		(at 26.289 -248.158 180)
		(property "Reference" "PC42"
			(at 0 0 180)
			(layer "F.SilkS")
			(hide yes)
			(effects
				(font
					(size 1.27 1.27)
				)
			)
		)
		(property "Value" "SC22P50V3JN-DLGP"
			(at 0 -2.8194 180)
			(unlocked yes)
			(layer "F.Fab")
			(hide yes)
			(effects
				(font
					(size 1.016 1.016)
					(thickness 0.1524)
				)
			)
		)
		(property "Device Type" "C603H36"
			(at 0 -4.3434 180)
			(unlocked yes)
			(layer "F.Fab")
			(hide yes)
			(effects
				(font
					(size 1.016 1.016)
					(thickness 0.1524)
				)
			)
		)
		(duplicate_pad_numbers_are_jumpers no)
		(fp_line
			(start 0.508 0)
			(end -0.508 0)
			(stroke
				(width 0.2032)
				(type default)
			)
			(layer "F.SilkS")
		)
		(fp_rect
			(start -0.5842 1.3335)
			(end 0.5842 -1.3335)
			(stroke
				(width 0)
				(type default)
			)
			(fill no)
			(layer "F.CrtYd")
		)
		(fp_rect
			(start -0.5842 1.3335)
			(end 0.5842 -1.3335)
			(stroke
				(width 0)
				(type default)
			)
			(fill no)
			(layer "F.Fab")
		)
		(pad "1" smd custom
			(at 0 -0.762 180)
			(size 0.2159 0.2159)
			(layers "F.Cu" "F.Mask" "F.Paste")
			(net "P3V3_LX_COPPER")
			(options
				(clearance outline)
				(anchor circle)
			)
			(primitives
				(gr_poly
					(pts
						(arc
							(start -0.3302 -0.4318)
							(mid -0.402042 -0.402042)
							(end -0.4318 -0.3302)
						)
						(arc
							(start -0.4318 0.3302)
							(mid -0.402042 0.402042)
							(end -0.3302 0.4318)
						)
						(arc
							(start 0.3302 0.4318)
							(mid 0.402042 0.402042)
							(end 0.4318 0.3302)
						)
						(arc
							(start 0.4318 -0.3302)
							(mid 0.402042 -0.402042)
							(end 0.3302 -0.4318)
						)
					)
					(width 0)
					(fill yes)
				)
			)
		)
		(pad "2" smd custom
			(at 0 0.762 180)
			(size 0.2159 0.2159)
			(layers "F.Cu" "F.Mask" "F.Paste")
			(net "P3V3_FB")
			(options
				(clearance outline)
				(anchor circle)
			)
			(primitives
				(gr_poly
					(pts
						(arc
							(start -0.3302 -0.4318)
							(mid -0.402042 -0.402042)
							(end -0.4318 -0.3302)
						)
						(arc
							(start -0.4318 0.3302)
							(mid -0.402042 0.402042)
							(end -0.3302 0.4318)
						)
						(arc
							(start 0.3302 0.4318)
							(mid 0.402042 0.402042)
							(end 0.4318 0.3302)
						)
						(arc
							(start 0.4318 -0.3302)
							(mid 0.402042 -0.402042)
							(end 0.3302 -0.4318)
						)
					)
					(width 0)
					(fill yes)
				)
			)
		)
	)
	(footprint ""
		(layer "F.Cu")
		(at 4.040124 -482.700076 -90)
		(property "Reference" "CN1"
			(at 0 0 270)
			(layer "F.SilkS")
			(hide yes)
			(effects
				(font
					(size 1.27 1.27)
				)
			)
		)
		(property "Value" "JWT-CON5-42-GP"
			(at -7.8105 2.9591 270)
			(unlocked yes)
			(layer "F.Fab")
			(hide yes)
			(effects
				(font
					(size 1.016 1.016)
					(thickness 0.1524)
				)
			)
		)
		(property "Device Type" "A2541WR0-1TX5PA-6T-0E"
			(at -7.8105 1.4351 270)
			(unlocked yes)
			(layer "F.Fab")
			(hide yes)
			(effects
				(font
					(size 1.016 1.016)
					(thickness 0.1524)
				)
			)
		)
		(duplicate_pad_numbers_are_jumpers no)
		(fp_line
			(start -6.604 10.287)
			(end 6.604 10.287)
			(stroke
				(width 0.1524)
				(type default)
			)
			(layer "F.SilkS")
		)
		(fp_line
			(start 6.604 10.287)
			(end 6.604 -0.9652)
			(stroke
				(width 0.1524)
				(type default)
			)
			(layer "F.SilkS")
		)
		(fp_line
			(start -6.604 -0.9652)
			(end -6.604 10.287)
			(stroke
				(width 0.1524)
				(type default)
			)
			(layer "F.SilkS")
		)
		(fp_line
			(start 6.604 -0.9652)
			(end -6.604 -0.9652)
			(stroke
				(width 0.1524)
				(type default)
			)
			(layer "F.SilkS")
		)
		(fp_line
			(start -6.731 -1.0922)
			(end -6.731 0.1778)
			(stroke
				(width 0.4064)
				(type default)
			)
			(layer "F.SilkS")
		)
		(fp_line
			(start -5.461 -1.0922)
			(end -6.731 -1.0922)
			(stroke
				(width 0.4064)
				(type default)
			)
			(layer "F.SilkS")
		)
		(fp_circle
			(center -5.08 0)
			(end -5.08 -1.0668)
			(stroke
				(width 0.3048)
				(type default)
			)
			(fill no)
			(layer "F.SilkS")
		)
		(fp_circle
			(center -2.54 0)
			(end -2.54 -1.0668)
			(stroke
				(width 0.3048)
				(type default)
			)
			(fill no)
			(layer "F.SilkS")
		)
		(fp_circle
			(center 0 0)
			(end 0 -1.0668)
			(stroke
				(width 0.3048)
				(type default)
			)
			(fill no)
			(layer "F.SilkS")
		)
		(fp_circle
			(center 2.54 0)
			(end 2.54 -1.0668)
			(stroke
				(width 0.3048)
				(type default)
			)
			(fill no)
			(layer "F.SilkS")
		)
		(fp_circle
			(center 5.08 0)
			(end 5.08 -1.0668)
			(stroke
				(width 0.3048)
				(type default)
			)
			(fill no)
			(layer "F.SilkS")
		)
		(fp_rect
			(start -6.35 10.033)
			(end 6.35 -0.3302)
			(stroke
				(width 0)
				(type default)
			)
			(fill no)
			(layer "F.CrtYd")
		)
		(fp_poly
			(pts
				(xy -6.35 -0.3302) (xy 6.858 -0.3302) (xy 6.858 -1.2192) (xy -6.858 -1.2192) (xy -6.858 10.541)
				(xy 6.858 10.541) (xy 6.858 -0.3175) (xy 6.35 -0.3175) (xy 6.35 10.033) (xy -6.35 10.033)
			)
			(stroke
				(width 0)
				(type default)
			)
			(fill no)
			(layer "F.CrtYd")
		)
		(fp_rect
			(start -6.858 10.541)
			(end 6.858 -1.2192)
			(stroke
				(width 0)
				(type default)
			)
			(fill no)
			(layer "F.Fab")
		)
		(pad "1" thru_hole circle
			(at -5.08 0 270)
			(size 1.4224 1.4224)
			(drill 1.016)
			(layers "*.Cu" "*.Mask")
			(remove_unused_layers no)
			(net "GND")
			(clearance 0.1524)
			(thermal_gap 0.1524)
		)
		(pad "2" thru_hole circle
			(at -2.54 0 270)
			(size 1.4224 1.4224)
			(drill 1.016)
			(layers "*.Cu" "*.Mask")
			(remove_unused_layers no)
			(net "P12V_FAN1")
			(clearance 0.1524)
			(thermal_gap 0.1524)
		)
		(pad "3" thru_hole circle
			(at 0 0 270)
			(size 1.4224 1.4224)
			(drill 1.016)
			(layers "*.Cu" "*.Mask")
			(remove_unused_layers no)
			(net "FAN_TACH2")
			(clearance 0.1524)
			(thermal_gap 0.1524)
		)
		(pad "4" thru_hole circle
			(at 2.54 0 270)
			(size 1.4224 1.4224)
			(drill 1.016)
			(layers "*.Cu" "*.Mask")
			(remove_unused_layers no)
			(net "PWM_OUT_FAN1_NET")
			(clearance 0.1524)
			(thermal_gap 0.1524)
		)
		(pad "5" thru_hole circle
			(at 5.08 0 270)
			(size 1.4224 1.4224)
			(drill 1.016)
			(layers "*.Cu" "*.Mask")
			(remove_unused_layers no)
			(net "FAN_TACH1")
			(clearance 0.1524)
			(thermal_gap 0.1524)
		)
	)
	(footprint ""
		(layer "F.Cu")
		(at 17.8816 -253.9492 90)
		(property "Reference" "R90"
			(at 0 0 90)
			(layer "F.SilkS")
			(hide yes)
			(effects
				(font
					(size 1.27 1.27)
				)
			)
		)
		(property "Value" "10KR2F-2-GP"
			(at 0.064008 -3.993896 90)
			(unlocked yes)
			(layer "F.Fab")
			(hide yes)
			(effects
				(font
					(size 1.016 1.016)
					(thickness 0.1524)
				)
			)
		)
		(property "Device Type" "R402H16"
			(at 0.064008 -5.517896 90)
			(unlocked yes)
			(layer "F.Fab")
			(hide yes)
			(effects
				(font
					(size 1.016 1.016)
					(thickness 0.1524)
				)
			)
		)
		(duplicate_pad_numbers_are_jumpers no)
		(fp_line
			(start 0.508 -0.9398)
			(end -0.508 -0.9398)
			(stroke
				(width 0.1524)
				(type default)
			)
			(layer "F.SilkS")
		)
		(fp_line
			(start -0.508 -0.9398)
			(end -0.508 0.9398)
			(stroke
				(width 0.1524)
				(type default)
			)
			(layer "F.SilkS")
		)
		(fp_rect
			(start -0.508 0.9398)
			(end 0.508 -0.9398)
			(stroke
				(width 0)
				(type default)
			)
			(fill no)
			(layer "F.CrtYd")
		)
		(fp_rect
			(start -0.508 0.9398)
			(end 0.508 -0.9398)
			(stroke
				(width 0)
				(type default)
			)
			(fill no)
			(layer "F.Fab")
		)
		(pad "1" smd custom
			(at 0 -0.4445 90)
			(size 0.1397 0.1397)
			(layers "F.Cu" "F.Mask" "F.Paste")
			(net "FANIN_5")
			(options
				(clearance outline)
				(anchor circle)
			)
			(primitives
				(gr_poly
					(pts
						(arc
							(start -0.1778 -0.2794)
							(mid -0.249642 -0.249642)
							(end -0.2794 -0.1778)
						)
						(arc
							(start -0.2794 0.1778)
							(mid -0.249642 0.249642)
							(end -0.1778 0.2794)
						)
						(arc
							(start 0.1778 0.2794)
							(mid 0.249642 0.249642)
							(end 0.2794 0.1778)
						)
						(arc
							(start 0.2794 -0.1778)
							(mid 0.249642 -0.249642)
							(end 0.1778 -0.2794)
						)
					)
					(width 0)
					(fill yes)
				)
			)
		)
		(pad "2" smd custom
			(at 0 0.4445 90)
			(size 0.1397 0.1397)
			(layers "F.Cu" "F.Mask" "F.Paste")
			(net "GND")
			(options
				(clearance outline)
				(anchor circle)
			)
			(primitives
				(gr_poly
					(pts
						(arc
							(start -0.1778 -0.2794)
							(mid -0.249642 -0.249642)
							(end -0.2794 -0.1778)
						)
						(arc
							(start -0.2794 0.1778)
							(mid -0.249642 0.249642)
							(end -0.1778 0.2794)
						)
						(arc
							(start 0.1778 0.2794)
							(mid 0.249642 0.249642)
							(end 0.2794 0.1778)
						)
						(arc
							(start 0.2794 -0.1778)
							(mid 0.249642 -0.249642)
							(end 0.1778 -0.2794)
						)
					)
					(width 0)
					(fill yes)
				)
			)
		)
	)
)
